# T6G (Grand Teton) — schematic netlist excerpt (pin names and nets, part order shuffled) for the footprints in the layout excerpt that follows; sources: Cadence DE-HDL packaged netlist, KiCad conversion of 04192023_DAF0TMB3IC0_F0TG_MB_C_brd_V02_OCP.brd

J100  SCONN288_DDR506112002KQ  IO  pkg DDR288S_1-1VXC  page 106
  VIN_BULK0  = P12V_MEM_CPU1
  RFU0  = NC
  VIN_MGMT  = P3V3_AUX
  HSCL  = I3C_SPD_DDRI_CPU1_SCL
  HSDA  = I3C_SPD_DDRI_CPU1_SDA
  VSS0  = GND
  DQ0_A  = M_I_CPU1_SA_DQ<0>
  VSS1  = GND
  DQ1_A  = M_I_CPU1_SA_DQ<1>
  VSS2  = GND
  DQS0_A_T  = M_I_CPU1_SA_DQS_DP<0>
  DQS0_A_C  = M_I_CPU1_SA_DQS_DN<0>
  VSS3  = GND
  DQ4_A  = M_I_CPU1_SA_DQ<4>
  VSS4  = GND
  DQ5_A  = M_I_CPU1_SA_DQ<5>
  VSS5  = GND
  DQ8_A  = M_I_CPU1_SA_DQ<8>
  VSS6  = GND
  DQ9_A  = M_I_CPU1_SA_DQ<9>
  VSS7  = GND
  DQS1_A_T  = M_I_CPU1_SA_DQS_DP<1>
  DQS1_A_C  = M_I_CPU1_SA_DQS_DN<1>
  VSS8  = GND
  DQ12_A  = M_I_CPU1_SA_DQ<12>
  VSS9  = GND
  DQ13_A  = M_I_CPU1_SA_DQ<13>
  VSS10  = GND
  DQ16_A  = M_I_CPU1_SA_DQ<16>
  VSS11  = GND
  DQ17_A  = M_I_CPU1_SA_DQ<17>
  VSS12  = GND
  DQS2_A_T  = M_I_CPU1_SA_DQS_DP<2>
  DQS2_A_C  = M_I_CPU1_SA_DQS_DN<2>
  VSS13  = GND
  DQ20_A  = M_I_CPU1_SA_DQ<20>
  VSS14  = GND
  DQ21_A  = M_I_CPU1_SA_DQ<21>
  VSS15  = GND
  DQ24_A  = M_I_CPU1_SA_DQ<24>
  VSS16  = GND
  DQ25_A  = M_I_CPU1_SA_DQ<25>
  VSS17  = GND
  DQS3_A_T  = M_I_CPU1_SA_DQS_DP<3>
  DQS3_A_C  = M_I_CPU1_SA_DQS_DN<3>
  VSS18  = GND
  DQ28_A  = M_I_CPU1_SA_DQ<28>
  VSS19  = GND
  DQ29_A  = M_I_CPU1_SA_DQ<29>
  VSS20  = GND
  CB0_A  = M_I_CPU1_SA_CB<0>
  VSS21  = GND
  CB1_A  = M_I_CPU1_SA_CB<1>
  VSS22  = GND
  DQS4_A_T  = M_I_CPU1_SA_DQS_DP<4>
  DQS4_A_C  = M_I_CPU1_SA_DQS_DN<4>
  VSS23  = GND
  CB4_A  = M_I_CPU1_SA_CB<4>
  VSS24  = GND
  CB5_A  = M_I_CPU1_SA_CB<5>
  VSS25  = GND
  ALERT_N  = M_I_CPU1_ALERT_N
  VSS26  = GND
  CS0_A_N  = M_I_CPU1_SA_CS_N<0>
  VSS27  = GND
  CA0_A  = M_I_CPU1_SA_CA<0>
  VSS28  = GND
  CA2_A  = M_I_CPU1_SA_CA<2>
  VSS29  = GND
  CA4_A  = M_I_CPU1_SA_CA<4>
  VSS30  = GND
  CA6_A  = M_I_CPU1_SA_CA<6>
  VSS31  = GND
  PAR_A  = M_I_CPU1_SA_PAR
  VSS32  = GND
  CA0_B  = M_I_CPU1_SB_CA<0>
  VSS33  = GND
  CA2_B  = M_I_CPU1_SB_CA<2>
  VSS34  = GND
  CA4_B  = M_I_CPU1_SB_CA<4>
  VSS35  = GND
  CA6_B  = M_I_CPU1_SB_CA<6>
  VSS36  = GND
  CS0_B_N  = M_I_CPU1_SB_CS_N<0>
  VSS37  = GND
  \lbd||rsp_a_n\  = M_I_CPU1_SA_RSP<0>
  \lbs||rsp_b_n\  = M_I_CPU1_SB_RSP<0>
  VSS38  = GND
  CB4_B  = M_I_CPU1_SB_CB<4>
  VSS39  = GND
  CB5_B  = M_I_CPU1_SB_CB<5>
  VSS40  = GND
  \dqs9_b_t||tdqs9_b_t||dbi4_b_n\  = M_I_CPU1_SB_DQS_DP<9>
  \dqs9_b_c||tdqs9_b_c\  = M_I_CPU1_SB_DQS_DN<9>
  VSS41  = GND
  CB0_B  = M_I_CPU1_SB_CB<0>
  VSS42  = GND
  CB1_B  = M_I_CPU1_SB_CB<1>
  VSS43  = GND
  DQ0_B  = M_I_CPU1_SB_DQ<0>
  VSS44  = GND
  DQ1_B  = M_I_CPU1_SB_DQ<1>
  VSS45  = GND
  DQS0_B_T  = M_I_CPU1_SB_DQS_DP<0>
  DQS0_B_C  = M_I_CPU1_SB_DQS_DN<0>
  VSS46  = GND
  DQ4_B  = M_I_CPU1_SB_DQ<4>
  VSS47  = GND
  DQ5_B  = M_I_CPU1_SB_DQ<5>
  VSS48  = GND
  DQ8_B  = M_I_CPU1_SB_DQ<8>
  VSS49  = GND
  DQ9_B  = M_I_CPU1_SB_DQ<9>
  VSS50  = GND
  DQS1_B_T  = M_I_CPU1_SB_DQS_DP<1>
  DQS1_B_C  = M_I_CPU1_SB_DQS_DN<1>
  VSS51  = GND
  DQ12_B  = M_I_CPU1_SB_DQ<12>
  VSS52  = GND
  DQ13_B  = M_I_CPU1_SB_DQ<13>
  VSS53  = GND
  DQ16_B  = M_I_CPU1_SB_DQ<16>
  VSS54  = GND
  DQ17_B  = M_I_CPU1_SB_DQ<17>
  VSS55  = GND
  DQS2_B_T  = M_I_CPU1_SB_DQS_DP<2>
  DQS2_B_C  = M_I_CPU1_SB_DQS_DN<2>
  VSS56  = GND
  DQ20_B  = M_I_CPU1_SB_DQ<20>
  VSS57  = GND
  DQ21_B  = M_I_CPU1_SB_DQ<21>
  VSS58  = GND
  DQ24_B  = M_I_CPU1_SB_DQ<24>
  VSS59  = GND
  DQ25_B  = M_I_CPU1_SB_DQ<25>
  VSS60  = GND
  DQS3_B_T  = M_I_CPU1_SB_DQS_DP<3>
  DQS3_B_C  = M_I_CPU1_SB_DQS_DN<3>
  VSS61  = GND
  DQ28_B  = M_I_CPU1_SB_DQ<28>
  VSS62  = GND
  DQ29_B  = M_I_CPU1_SB_DQ<29>
  VSS63  = GND
  RFU1  = NC
  VIN_BULK1  = P12V_MEM_CPU1
  VIN_BULK2  = P12V_MEM_CPU1
  \pwr_good||fail_n\  = PWRGD_CHI_CPU1_DIMM
  HAS  = PD_CHI_CPU1_DIMM_SAA
  RFU2  = NC
  RFU3  = NC
  VSS64  = GND
  DQ2_A  = M_I_CPU1_SA_DQ<2>
  VSS65  = GND
  DQ3_A  = M_I_CPU1_SA_DQ<3>
  VSS66  = GND
  \dqs5_a_c||tdqs5_a_c||dqs5_a_t||tdqs5_a_t\  = M_I_CPU1_SA_DQS_DN<5>
  \dqs5_a_t||tdqs5_a_t\  = M_I_CPU1_SA_DQS_DP<5>
  VSS67  = GND
  DQ6_A  = M_I_CPU1_SA_DQ<6>
  VSS68  = GND
  DQ7_A  = M_I_CPU1_SA_DQ<7>
  VSS69  = GND
  DQ10_A  = M_I_CPU1_SA_DQ<10>
  VSS70  = GND
  DQ11_A  = M_I_CPU1_SA_DQ<11>
  VSS71  = GND
  \dqs6_a_c||tdqs6_a_c||dqs6_a_t||tdqs6_a_t\  = M_I_CPU1_SA_DQS_DN<6>
  \dqs6_a_t||tdqs6_a_t\  = M_I_CPU1_SA_DQS_DP<6>
  VSS72  = GND
  DQ14_A  = M_I_CPU1_SA_DQ<14>
  VSS73  = GND
  DQ15_A  = M_I_CPU1_SA_DQ<15>
  VSS74  = GND
  DQ18_A  = M_I_CPU1_SA_DQ<18>
  VSS75  = GND
  DQ19_A  = M_I_CPU1_SA_DQ<19>
  VSS76  = GND
  \dqs7_a_c||tdqs7_a_c\  = M_I_CPU1_SA_DQS_DN<7>
  \dqs7_a_t||tdqs7_a_t\  = M_I_CPU1_SA_DQS_DP<7>
  VSS77  = GND
  DQ22_A  = M_I_CPU1_SA_DQ<22>
  VSS78  = GND
  DQ23_A  = M_I_CPU1_SA_DQ<23>
  VSS79  = GND
  DQ26_A  = M_I_CPU1_SA_DQ<26>
  VSS80  = GND
  DQ27_A  = M_I_CPU1_SA_DQ<27>
  VSS81  = GND
  \dqs8_a_c||tdqs8_a_c\  = M_I_CPU1_SA_DQS_DN<8>
  \dqs8_a_t||tdqs8_a_t\  = M_I_CPU1_SA_DQS_DP<8>
  VSS82  = GND
  DQ30_A  = M_I_CPU1_SA_DQ<30>
  VSS83  = GND
  DQ31_A  = M_I_CPU1_SA_DQ<31>
  VSS84  = GND
  CB2_A  = M_I_CPU1_SA_CB<2>
  VSS85  = GND
  CB3_A  = M_I_CPU1_SA_CB<3>
  VSS86  = GND
  \dqs9_a_c||tdqs9_a_c\  = M_I_CPU1_SA_DQS_DN<9>
  \dqs9_a_t||tdqs9_a_t\  = M_I_CPU1_SA_DQS_DP<9>
  VSS87  = GND
  CB6_A  = M_I_CPU1_SA_CB<6>
  VSS88  = GND
  CB7_A  = M_I_CPU1_SA_CB<7>
  VSS89  = GND
  RESET_N  = M_I_CPU1_RESET_N
  VSS90  = GND
  CS1_A_N  = M_I_CPU1_SA_CS_N<1>
  VSS91  = GND
  CA1_A  = M_I_CPU1_SA_CA<1>
  VSS92  = GND
  CA3_A  = M_I_CPU1_SA_CA<3>
  VSS93  = GND
  CA5_A  = M_I_CPU1_SA_CA<5>
  VSS94  = GND
  CK_T  = M_I_CPU1_CLK_DP<0>
  CK_C  = M_I_CPU1_CLK_DN<0>
  VSS95  = GND
  RFU4  = NC
  CA1_B  = M_I_CPU1_SB_CA<1>
  VSS96  = GND
  CA3_B  = M_I_CPU1_SB_CA<3>
  VSS97  = GND
  CA5_B  = M_I_CPU1_SB_CA<5>
  VSS98  = GND
  PAR_B  = M_I_CPU1_SB_PAR
  VSS99  = GND
  CS1_B_N  = M_I_CPU1_SB_CS_N<1>
  VSS100  = GND
  RFU5  = NC
  RFU6  = NC
  VSS101  = GND
  CB6_B  = M_I_CPU1_SB_CB<6>
  VSS102  = GND
  CB7_B  = M_I_CPU1_SB_CB<7>
  VSS103  = GND
  DQS4_B_C  = M_I_CPU1_SB_DQS_DN<4>
  DQS4_B_T  = M_I_CPU1_SB_DQS_DP<4>
  VSS104  = GND
  CB2_B  = M_I_CPU1_SB_CB<2>
  VSS105  = GND
  CB3_B  = M_I_CPU1_SB_CB<3>
  VSS106  = GND
  DQ2_B  = M_I_CPU1_SB_DQ<2>
  VSS107  = GND
  DQ3_B  = M_I_CPU1_SB_DQ<3>
  VSS108  = GND
  \dqs5_b_c||tdqs5_b_c\  = M_I_CPU1_SB_DQS_DN<5>
  \dqs5_b_t||tdqs5_b_t\  = M_I_CPU1_SB_DQS_DP<5>
  VSS109  = GND
  DQ6_B  = M_I_CPU1_SB_DQ<6>
  VSS110  = GND
  DQ7_B  = M_I_CPU1_SB_DQ<7>
  VSS111  = GND
  DQ10_B  = M_I_CPU1_SB_DQ<10>
  VSS112  = GND
  DQ11_B  = M_I_CPU1_SB_DQ<11>
  VSS113  = GND
  \dqs6_b_c||tdqs6_b_c\  = M_I_CPU1_SB_DQS_DN<6>
  \dqs6_b_t||tdqs6_b_t\  = M_I_CPU1_SB_DQS_DP<6>
  VSS114  = GND
  DQ14_B  = M_I_CPU1_SB_DQ<14>
  VSS115  = GND
  DQ15_B  = M_I_CPU1_SB_DQ<15>
  VSS116  = GND
  DQ18_B  = M_I_CPU1_SB_DQ<18>
  VSS117  = GND
  DQ19_B  = M_I_CPU1_SB_DQ<19>
  VSS118  = GND
  \dqs7_b_c||tdqs7_b_c\  = M_I_CPU1_SB_DQS_DN<7>
  \dqs7_b_t||tdqs7_b_t\  = M_I_CPU1_SB_DQS_DP<7>
  VSS119  = GND
  DQ22_B  = M_I_CPU1_SB_DQ<22>
  VSS120  = GND
  DQ23_B  = M_I_CPU1_SB_DQ<23>
  VSS121  = GND
  DQ26_B  = M_I_CPU1_SB_DQ<26>
  VSS122  = GND
  DQ27_B  = M_I_CPU1_SB_DQ<27>
  VSS123  = GND
  \dqs8_b_c||tdqs8_b_c\  = M_I_CPU1_SB_DQS_DN<8>
  \dqs8_b_t||tdqs8_b_t\  = M_I_CPU1_SB_DQS_DP<8>
  VSS124  = GND
  DQ30_B  = M_I_CPU1_SB_DQ<30>
  VSS125  = GND
  DQ31_B  = M_I_CPU1_SB_DQ<31>
  VSS126  = GND
  G1  = GND
  G2  = GND
  G3  = GND

(kicad_pcb
	(version 20260206)
	(generator "pcbnew")
	(generator_version "10.0")
	(general
		(thickness 1.6)
		(legacy_teardrops no)
	)
	(paper "A4")
	(title_block
		(title "04192023_DAF0TMB3IC0_F0TG_MB_C_brd_V02_OCP.brd")
		(comment 1 "Grand Teton / footprint 230 of 8354 (J100), pads 231-276 of 291")
	)
	(layers
		(0 "F.Cu" signal "TOP")
		(4 "In1.Cu" signal "GND")
		(6 "In2.Cu" signal "IN1")
		(8 "In3.Cu" signal "GND1")
		(10 "In4.Cu" signal "IN2")
		(12 "In5.Cu" signal "GND2")
		(14 "In6.Cu" signal "IN3")
		(16 "In7.Cu" signal "GND3")
		(18 "In8.Cu" signal "VCC")
		(20 "In9.Cu" signal "VCC1")
		(22 "In10.Cu" signal "GND4")
		(24 "In11.Cu" signal "IN4")
		(26 "In12.Cu" signal "GND5")
		(28 "In13.Cu" signal "IN5")
		(30 "In14.Cu" signal "GND6")
		(32 "In15.Cu" signal "IN6")
		(34 "In16.Cu" signal "GND7")
		(2 "B.Cu" signal "BOTTOM")
		(9 "F.Adhes" user "F.Adhesive")
		(11 "B.Adhes" user "B.Adhesive")
		(13 "F.Paste" user "Package Geometry/Pastemask Top")
		(15 "B.Paste" user "Package Geometry/Pastemask Bottom")
		(5 "F.SilkS" user "Ref Des/Silkscreen Top")
		(7 "B.SilkS" user "Ref Des/Silkscreen Bottom")
		(1 "F.Mask" user "Board Geometry/Soldermask Top")
		(3 "B.Mask" user "Board Geometry/Soldermask Bottom")
		(17 "Dwgs.User" user "User.Drawings")
		(19 "Cmts.User" user "User.Comments")
		(21 "Eco1.User" user "User.Eco1")
		(23 "Eco2.User" user "User.Eco2")
		(25 "Edge.Cuts" user "Board Geometry/Outline")
		(27 "Margin" user)
		(31 "F.CrtYd" user "Package Geometry/Place Bound Top")
		(29 "B.CrtYd" user "Package Geometry/Place Bound Bottom")
		(35 "F.Fab" user "Ref Des/Assembly Top")
		(33 "B.Fab" user "Ref Des/Assembly Bottom")
	)
	(footprint ""
		(layer "F.Cu")
		(at 181.566058 -255.560322 180)
		(property "Reference" "J100"
			(at -2.7178 -81.857088 0)
			(unlocked yes)
			(layer "F.SilkS")
			(effects
				(font
					(size 0.7874 0.5842)
					(thickness 0.1524)
				)
			)
		)
		(property "Value" ""
			(at 0 0 180)
			(layer "F.Fab")
			(effects
				(font
					(size 1.27 1.27)
				)
			)
		)
		(duplicate_pad_numbers_are_jumpers no)
		(pad "231" smd rect
			(at 2.050034 14.875002 90)
			(size 0.519938 1.4986)
			(layers "F.Cu" "F.Mask" "F.Paste")
			(net "Net_2373")
		)
		(pad "232" smd rect
			(at 2.050034 15.724886 90)
			(size 0.519938 1.4986)
			(layers "F.Cu" "F.Mask" "F.Paste")
			(net "Net_2374")
		)
		(pad "233" smd rect
			(at 2.050034 16.575024 90)
			(size 0.519938 1.4986)
			(layers "F.Cu" "F.Mask" "F.Paste")
			(net "GND")
		)
		(pad "234" smd rect
			(at 2.050034 17.424908 90)
			(size 0.519938 1.4986)
			(layers "F.Cu" "F.Mask" "F.Paste")
			(net "M_I_CPU1_SB_CB<6>")
		)
		(pad "235" smd rect
			(at 2.050034 18.275046 90)
			(size 0.519938 1.4986)
			(layers "F.Cu" "F.Mask" "F.Paste")
			(net "GND")
		)
		(pad "236" smd rect
			(at 2.050034 19.12493 90)
			(size 0.519938 1.4986)
			(layers "F.Cu" "F.Mask" "F.Paste")
			(net "M_I_CPU1_SB_CB<7>")
		)
		(pad "237" smd rect
			(at 2.050034 19.975068 90)
			(size 0.519938 1.4986)
			(layers "F.Cu" "F.Mask" "F.Paste")
			(net "GND")
		)
		(pad "238" smd rect
			(at 2.050034 20.824952 90)
			(size 0.519938 1.4986)
			(layers "F.Cu" "F.Mask" "F.Paste")
			(net "M_I_CPU1_SB_DQS_DN<4>")
		)
		(pad "239" smd rect
			(at 2.050034 21.67509 90)
			(size 0.519938 1.4986)
			(layers "F.Cu" "F.Mask" "F.Paste")
			(net "M_I_CPU1_SB_DQS_DP<4>")
		)
		(pad "240" smd rect
			(at 2.050034 22.524974 90)
			(size 0.519938 1.4986)
			(layers "F.Cu" "F.Mask" "F.Paste")
			(net "GND")
		)
		(pad "241" smd rect
			(at 2.050034 23.375112 90)
			(size 0.519938 1.4986)
			(layers "F.Cu" "F.Mask" "F.Paste")
			(net "M_I_CPU1_SB_CB<2>")
		)
		(pad "242" smd rect
			(at 2.050034 24.224996 90)
			(size 0.519938 1.4986)
			(layers "F.Cu" "F.Mask" "F.Paste")
			(net "GND")
		)
		(pad "243" smd rect
			(at 2.050034 25.07488 90)
			(size 0.519938 1.4986)
			(layers "F.Cu" "F.Mask" "F.Paste")
			(net "M_I_CPU1_SB_CB<3>")
		)
		(pad "244" smd rect
			(at 2.050034 25.925018 90)
			(size 0.519938 1.4986)
			(layers "F.Cu" "F.Mask" "F.Paste")
			(net "GND")
		)
		(pad "245" smd rect
			(at 2.050034 26.774902 90)
			(size 0.519938 1.4986)
			(layers "F.Cu" "F.Mask" "F.Paste")
			(net "M_I_CPU1_SB_DQ<2>")
		)
		(pad "246" smd rect
			(at 2.050034 27.62504 90)
			(size 0.519938 1.4986)
			(layers "F.Cu" "F.Mask" "F.Paste")
			(net "GND")
		)
		(pad "247" smd rect
			(at 2.050034 28.474924 90)
			(size 0.519938 1.4986)
			(layers "F.Cu" "F.Mask" "F.Paste")
			(net "M_I_CPU1_SB_DQ<3>")
		)
		(pad "248" smd rect
			(at 2.050034 29.325062 90)
			(size 0.519938 1.4986)
			(layers "F.Cu" "F.Mask" "F.Paste")
			(net "GND")
		)
		(pad "249" smd rect
			(at 2.050034 30.174946 90)
			(size 0.519938 1.4986)
			(layers "F.Cu" "F.Mask" "F.Paste")
			(net "M_I_CPU1_SB_DQS_DN<5>")
		)
		(pad "250" smd rect
			(at 2.050034 31.025084 90)
			(size 0.519938 1.4986)
			(layers "F.Cu" "F.Mask" "F.Paste")
			(net "M_I_CPU1_SB_DQS_DP<5>")
		)
		(pad "251" smd rect
			(at 2.050034 31.874968 90)
			(size 0.519938 1.4986)
			(layers "F.Cu" "F.Mask" "F.Paste")
			(net "GND")
		)
		(pad "252" smd rect
			(at 2.050034 32.725106 90)
			(size 0.519938 1.4986)
			(layers "F.Cu" "F.Mask" "F.Paste")
			(net "M_I_CPU1_SB_DQ<6>")
		)
		(pad "253" smd rect
			(at 2.050034 33.57499 90)
			(size 0.519938 1.4986)
			(layers "F.Cu" "F.Mask" "F.Paste")
			(net "GND")
		)
		(pad "254" smd rect
			(at 2.050034 34.425128 90)
			(size 0.519938 1.4986)
			(layers "F.Cu" "F.Mask" "F.Paste")
			(net "M_I_CPU1_SB_DQ<7>")
		)
		(pad "255" smd rect
			(at 2.050034 35.275012 90)
			(size 0.519938 1.4986)
			(layers "F.Cu" "F.Mask" "F.Paste")
			(net "GND")
		)
		(pad "256" smd rect
			(at 2.050034 36.124896 90)
			(size 0.519938 1.4986)
			(layers "F.Cu" "F.Mask" "F.Paste")
			(net "M_I_CPU1_SB_DQ<10>")
		)
		(pad "257" smd rect
			(at 2.050034 36.975034 90)
			(size 0.519938 1.4986)
			(layers "F.Cu" "F.Mask" "F.Paste")
			(net "GND")
		)
		(pad "258" smd rect
			(at 2.050034 37.824918 90)
			(size 0.519938 1.4986)
			(layers "F.Cu" "F.Mask" "F.Paste")
			(net "M_I_CPU1_SB_DQ<11>")
		)
		(pad "259" smd rect
			(at 2.050034 38.675056 90)
			(size 0.519938 1.4986)
			(layers "F.Cu" "F.Mask" "F.Paste")
			(net "GND")
		)
		(pad "260" smd rect
			(at 2.050034 39.52494 90)
			(size 0.519938 1.4986)
			(layers "F.Cu" "F.Mask" "F.Paste")
			(net "M_I_CPU1_SB_DQS_DN<6>")
		)
		(pad "261" smd rect
			(at 2.050034 40.375078 90)
			(size 0.519938 1.4986)
			(layers "F.Cu" "F.Mask" "F.Paste")
			(net "M_I_CPU1_SB_DQS_DP<6>")
		)
		(pad "262" smd rect
			(at 2.050034 41.224962 90)
			(size 0.519938 1.4986)
			(layers "F.Cu" "F.Mask" "F.Paste")
			(net "GND")
		)
		(pad "263" smd rect
			(at 2.050034 42.0751 90)
			(size 0.519938 1.4986)
			(layers "F.Cu" "F.Mask" "F.Paste")
			(net "M_I_CPU1_SB_DQ<14>")
		)
		(pad "264" smd rect
			(at 2.050034 42.924984 90)
			(size 0.519938 1.4986)
			(layers "F.Cu" "F.Mask" "F.Paste")
			(net "GND")
		)
		(pad "265" smd rect
			(at 2.050034 43.775122 90)
			(size 0.519938 1.4986)
			(layers "F.Cu" "F.Mask" "F.Paste")
			(net "M_I_CPU1_SB_DQ<15>")
		)
		(pad "266" smd rect
			(at 2.050034 44.625006 90)
			(size 0.519938 1.4986)
			(layers "F.Cu" "F.Mask" "F.Paste")
			(net "GND")
		)
		(pad "267" smd rect
			(at 2.050034 45.47489 90)
			(size 0.519938 1.4986)
			(layers "F.Cu" "F.Mask" "F.Paste")
			(net "M_I_CPU1_SB_DQ<18>")
		)
		(pad "268" smd rect
			(at 2.050034 46.325028 90)
			(size 0.519938 1.4986)
			(layers "F.Cu" "F.Mask" "F.Paste")
			(net "GND")
		)
		(pad "269" smd rect
			(at 2.050034 47.174912 90)
			(size 0.519938 1.4986)
			(layers "F.Cu" "F.Mask" "F.Paste")
			(net "M_I_CPU1_SB_DQ<19>")
		)
		(pad "270" smd rect
			(at 2.050034 48.02505 90)
			(size 0.519938 1.4986)
			(layers "F.Cu" "F.Mask" "F.Paste")
			(net "GND")
		)
		(pad "271" smd rect
			(at 2.050034 48.874934 90)
			(size 0.519938 1.4986)
			(layers "F.Cu" "F.Mask" "F.Paste")
			(net "M_I_CPU1_SB_DQS_DN<7>")
		)
		(pad "272" smd rect
			(at 2.050034 49.725072 90)
			(size 0.519938 1.4986)
			(layers "F.Cu" "F.Mask" "F.Paste")
			(net "M_I_CPU1_SB_DQS_DP<7>")
		)
		(pad "273" smd rect
			(at 2.050034 50.574956 90)
			(size 0.519938 1.4986)
			(layers "F.Cu" "F.Mask" "F.Paste")
			(net "GND")
		)
		(pad "274" smd rect
			(at 2.050034 51.425094 90)
			(size 0.519938 1.4986)
			(layers "F.Cu" "F.Mask" "F.Paste")
			(net "M_I_CPU1_SB_DQ<22>")
		)
		(pad "275" smd rect
			(at 2.050034 52.274978 90)
			(size 0.519938 1.4986)
			(layers "F.Cu" "F.Mask" "F.Paste")
			(net "GND")
		)
		(pad "276" smd rect
			(at 2.050034 53.125116 90)
			(size 0.519938 1.4986)
			(layers "F.Cu" "F.Mask" "F.Paste")
			(net "M_I_CPU1_SB_DQ<23>")
		)
	)
)
